# BASEBOARD_FAB2 (Tioga Pass) — schematic netlist excerpt (pin names and nets, part order shuffled) for the footprints in the layout excerpt that follows; sources: Cadence DE-HDL packaged netlist, KiCad conversion of Wiwynn_Tioga_Pass_MB.brd

J30W1  SKT-USB32-8-GP  pkg SOCKET-G4  page 253
  GND(0)  = GND
  SSTXP1  = USB3_P01_FB_TXP
  SSTXN1  = USB3_P01_FB_TXN
  VBUS(0)  = P5V_STBY_USBC
  CC1  = NC
  DP1  = NC
  DN1  = NC
  SBU1  = NC
  VBUS(1)  = P5V_STBY_USBC
  SSRXN2  = NC
  SSRXP2  = NC
  GND(1)  = GND
  GND(2)  = GND
  SSTXP2  = NC
  SSTXN2  = NC
  VBUS(2)  = P5V_STBY_USBC
  CC2  = NC
  DP2  = NC
  DN2  = NC
  SBU2  = NC
  VBUS(3)  = P5V_STBY_USBC
  SSRXN1  = USB3_P01_FB_RXN
  SSRXP1  = USB3_P01_FB_RXP
  GND(3)  = GND
  NP1  = NC
  NP2  = NC
  PTH1  = GND
  PTH2  = GND
  PTH3  = GND
  PTH4  = GND
  PTH5  = GND
  PTH6  = GND
  PTH7  = GND
  PTH8  = GND

(kicad_pcb
	(version 20260206)
	(generator "pcbnew")
	(generator_version "10.0")
	(general
		(thickness 1.6)
		(legacy_teardrops no)
	)
	(paper "A4")
	(title_block
		(title "Wiwynn_Tioga_Pass_MB.brd")
		(comment 1 "Tioga Pass / footprint 189 of 4770 (J30W1), pads 1-33 of 34")
	)
	(layers
		(0 "F.Cu" signal "TOP")
		(4 "In1.Cu" signal "L2GND")
		(6 "In2.Cu" signal "L3")
		(8 "In3.Cu" signal "L4GND")
		(10 "In4.Cu" signal "L5")
		(12 "In5.Cu" signal "L6GND")
		(14 "In6.Cu" signal "L7VCC")
		(16 "In7.Cu" signal "L8VCC")
		(18 "In8.Cu" signal "L9GND")
		(20 "In9.Cu" signal "L10")
		(22 "In10.Cu" signal "L11GND")
		(24 "In11.Cu" signal "L12")
		(26 "In12.Cu" signal "L13GND")
		(2 "B.Cu" signal "BOTTOM")
		(9 "F.Adhes" user "F.Adhesive")
		(11 "B.Adhes" user "B.Adhesive")
		(13 "F.Paste" user "Package Geometry/Pastemask Top")
		(15 "B.Paste" user "Package Geometry/Pastemask Bottom")
		(5 "F.SilkS" user "Ref Des/Silkscreen Top")
		(7 "B.SilkS" user "Ref Des/Silkscreen Bottom")
		(1 "F.Mask" user "Board Geometry/Soldermask Top")
		(3 "B.Mask" user "Board Geometry/Soldermask Bottom")
		(17 "Dwgs.User" user "User.Drawings")
		(19 "Cmts.User" user "User.Comments")
		(21 "Eco1.User" user "User.Eco1")
		(23 "Eco2.User" user "User.Eco2")
		(25 "Edge.Cuts" user "Board Geometry/Outline")
		(27 "Margin" user)
		(31 "F.CrtYd" user "Package Geometry/Place Bound Top")
		(29 "B.CrtYd" user "Package Geometry/Place Bound Bottom")
		(35 "F.Fab" user "Ref Des/Assembly Top")
		(33 "B.Fab" user "Ref Des/Assembly Bottom")
	)
	(footprint ""
		(layer "F.Cu")
		(at 497.05006 -57.079896 90)
		(property "Reference" "J30W1"
			(at 0 0 90)
			(layer "F.SilkS")
			(hide yes)
			(effects
				(font
					(size 1.27 1.27)
				)
			)
		)
		(property "Value" "*"
			(at 6.604 -3.1623 90)
			(unlocked yes)
			(layer "F.Fab")
			(hide yes)
			(effects
				(font
					(size 1.27 1.016)
					(thickness 0.1524)
				)
			)
		)
		(property "Device Type" "SKT-USB32-8-GP_SOCKET-G4-SKT-UA"
			(at 6.604 -4.6863 90)
			(unlocked yes)
			(layer "F.Fab")
			(hide yes)
			(effects
				(font
					(size 1.27 1.016)
					(thickness 0.1524)
				)
			)
		)
		(duplicate_pad_numbers_are_jumpers no)
		(pad "" np_thru_hole circle
			(at -3.350006 0 90)
			(size 0.254 0.254)
			(drill 0.762)
			(layers "*.Cu" "*.Mask")
			(clearance 0.6096)
			(thermal_gap 0.6096)
		)
		(pad "" np_thru_hole circle
			(at 3.150108 0 90)
			(size 0.254 0.254)
			(drill 0.6604)
			(layers "*.Cu" "*.Mask")
			(clearance 0.5588)
			(thermal_gap 0.5588)
		)
		(pad "A1" smd rect
			(at -2.750058 -0.8001 90)
			(size 0.3048 0.8128)
			(layers "F.Cu" "F.Mask" "F.Paste")
			(net "GND")
		)
		(pad "A2" smd rect
			(at -2.249932 -0.8001 90)
			(size 0.3048 0.8128)
			(layers "F.Cu" "F.Mask" "F.Paste")
			(net "USB3_P01_FB_TXP")
		)
		(pad "A3" smd rect
			(at -1.75006 -0.8001 90)
			(size 0.3048 0.8128)
			(layers "F.Cu" "F.Mask" "F.Paste")
			(net "USB3_P01_FB_TXN")
		)
		(pad "A4" smd rect
			(at -1.249934 -0.7493 90)
			(size 0.3048 0.7112)
			(layers "F.Cu" "F.Mask" "F.Paste")
			(net "P5V_STBY_USBC")
		)
		(pad "A5" smd rect
			(at -0.750062 -0.7493 90)
			(size 0.3048 0.7112)
			(layers "F.Cu" "F.Mask" "F.Paste")
			(net "Net_6503")
		)
		(pad "A6" smd rect
			(at -0.249936 -0.8001 90)
			(size 0.3048 0.8128)
			(layers "F.Cu" "F.Mask" "F.Paste")
			(net "Net_6499")
		)
		(pad "A7" smd rect
			(at 0.249936 -0.8001 90)
			(size 0.3048 0.8128)
			(layers "F.Cu" "F.Mask" "F.Paste")
			(net "Net_6501")
		)
		(pad "A8" smd rect
			(at 0.750062 -0.7493 90)
			(size 0.3048 0.7112)
			(layers "F.Cu" "F.Mask" "F.Paste")
			(net "Net_6495")
		)
		(pad "A9" smd rect
			(at 1.249934 -0.7493 90)
			(size 0.3048 0.7112)
			(layers "F.Cu" "F.Mask" "F.Paste")
			(net "P5V_STBY_USBC")
		)
		(pad "A10" smd rect
			(at 1.75006 -0.8001 90)
			(size 0.3048 0.8128)
			(layers "F.Cu" "F.Mask" "F.Paste")
			(net "Net_6493")
		)
		(pad "A11" smd rect
			(at 2.249932 -0.8001 90)
			(size 0.3048 0.8128)
			(layers "F.Cu" "F.Mask" "F.Paste")
			(net "Net_6492")
		)
		(pad "A12" smd custom
			(at 2.750058 -0.8001 90)
			(size 0.0762 0.0762)
			(layers "F.Cu" "F.Mask" "F.Paste")
			(net "GND")
			(options
				(clearance outline)
				(anchor circle)
			)
			(primitives
				(gr_poly
					(pts
						(xy -0.1524 0.4064) (xy -0.1524 -0.4064) (xy 0.1524 -0.4064)
						(arc
							(start 0.1524 0.284988)
							(mid 0.063554 0.338103)
							(end -0.014224 0.4064)
						)
					)
					(width 0)
					(fill yes)
				)
			)
		)
		(pad "B1" smd rect
			(at 2.724658 0.899922 90)
			(size 0.254 0.8128)
			(layers "F.Cu" "F.Mask" "F.Paste")
			(net "GND")
		)
		(pad "B2" smd rect
			(at 2.249932 0.899922 90)
			(size 0.3048 0.8128)
			(layers "F.Cu" "F.Mask" "F.Paste")
			(net "Net_380")
		)
		(pad "B3" smd rect
			(at 1.75006 0.899922 90)
			(size 0.3048 0.8128)
			(layers "F.Cu" "F.Mask" "F.Paste")
			(net "Net_381")
		)
		(pad "B4" smd rect
			(at 1.249934 0.899922 90)
			(size 0.3048 0.8128)
			(layers "F.Cu" "F.Mask" "F.Paste")
			(net "P5V_STBY_USBC")
		)
		(pad "B5" smd rect
			(at 0.750062 0.899922 90)
			(size 0.3048 0.8128)
			(layers "F.Cu" "F.Mask" "F.Paste")
			(net "Net_6502")
		)
		(pad "B6" smd rect
			(at 0.249936 0.899922 90)
			(size 0.3048 0.8128)
			(layers "F.Cu" "F.Mask" "F.Paste")
			(net "Net_6498")
		)
		(pad "B7" smd rect
			(at -0.249936 0.899922 90)
			(size 0.3048 0.8128)
			(layers "F.Cu" "F.Mask" "F.Paste")
			(net "Net_6500")
		)
		(pad "B8" smd rect
			(at -0.750062 0.899922 90)
			(size 0.3048 0.8128)
			(layers "F.Cu" "F.Mask" "F.Paste")
			(net "Net_6494")
		)
		(pad "B9" smd rect
			(at -1.249934 0.899922 90)
			(size 0.3048 0.8128)
			(layers "F.Cu" "F.Mask" "F.Paste")
			(net "P5V_STBY_USBC")
		)
		(pad "B10" smd rect
			(at -1.75006 0.899922 90)
			(size 0.3048 0.8128)
			(layers "F.Cu" "F.Mask" "F.Paste")
			(net "USB3_P01_FB_RXN")
		)
		(pad "B11" smd rect
			(at -2.249932 0.899922 90)
			(size 0.3048 0.8128)
			(layers "F.Cu" "F.Mask" "F.Paste")
			(net "USB3_P01_FB_RXP")
		)
		(pad "B12" smd rect
			(at -2.724658 0.899922 90)
			(size 0.254 0.8128)
			(layers "F.Cu" "F.Mask" "F.Paste")
			(net "GND")
		)
		(pad "PTH1" thru_hole custom
			(at -4.275074 -1.75006 90)
			(size 0.457329 0.457329)
			(drill 0.0254)
			(layers "*.Cu" "*.Mask")
			(remove_unused_layers no)
			(net "GND")
			(clearance 0.254)
			(thermal_gap 0.254)
			(options
				(clearance outline)
				(anchor circle)
			)
			(primitives
				(gr_poly
					(pts
						(arc
							(start 0.045974 1.070102)
							(mid -0.585696 1.112558)
							(end -0.9144 0.5715)
						)
						(arc
							(start -0.9144 -0.5715)
							(mid -0.735852 -1.002552)
							(end -0.3048 -1.1811)
						)
						(arc
							(start 0.3048 -1.1811)
							(mid 0.9144 -0.5715)
							(end 0.3048 0.0381)
						)
						(arc
							(start 0.3048 0.5715)
							(mid 0.301608 0.633547)
							(end 0.2921 0.694944)
						)
						(arc
							(start 0.2921 0.694944)
							(mid 0.1316 0.857963)
							(end 0.045974 1.070102)
						)
					)
					(width 0)
					(fill yes)
				)
			)
		)
		(pad "PTH2" thru_hole custom
			(at 4.275074 -1.75006 90)
			(size 0.457329 0.457329)
			(drill 0.0254)
			(layers "*.Cu" "*.Mask")
			(remove_unused_layers no)
			(net "GND")
			(clearance 0.254)
			(thermal_gap 0.254)
			(options
				(clearance outline)
				(anchor circle)
			)
			(primitives
				(gr_poly
					(pts
						(arc
							(start 0.9144 0.5715)
							(mid 0.3048 1.1811)
							(end -0.3048 0.5715)
						)
						(arc
							(start -0.3048 0.0381)
							(mid -0.9144 -0.5715)
							(end -0.3048 -1.1811)
						)
						(arc
							(start 0.3048 -1.1811)
							(mid 0.735852 -1.002552)
							(end 0.9144 -0.5715)
						)
					)
					(width 0)
					(fill yes)
				)
			)
		)
		(pad "PTH3" thru_hole oval
			(at -0.999998 -1.75006 90)
			(size 1.524 1.0414)
			(drill oval 0.8128 0.508
				(offset 0 -0.0889)
			)
			(layers "*.Cu" "*.Mask")
			(remove_unused_layers no)
			(net "GND")
			(clearance 0.1524)
			(thermal_gap 0.1524)
		)
		(pad "PTH4" thru_hole oval
			(at 0.999998 -1.75006 90)
			(size 1.524 1.0414)
			(drill oval 0.8128 0.508
				(offset 0 -0.0889)
			)
			(layers "*.Cu" "*.Mask")
			(remove_unused_layers no)
			(net "GND")
			(clearance 0.1524)
			(thermal_gap 0.1524)
		)
		(pad "PTH5" thru_hole circle
			(at -3.474974 1.27 90)
			(size 0.762 0.762)
			(drill 0.4572)
			(layers "*.Cu" "*.Mask")
			(remove_unused_layers no)
			(net "GND")
			(clearance 0.2032)
			(thermal_gap 0.2032)
		)
		(pad "PTH6" thru_hole circle
			(at 3.474974 1.27 90)
			(size 0.762 0.762)
			(drill 0.4572)
			(layers "*.Cu" "*.Mask")
			(remove_unused_layers no)
			(net "GND")
			(clearance 0.2032)
			(thermal_gap 0.2032)
		)
		(pad "PTH7" thru_hole oval
			(at -4.500118 3.50012 90)
			(size 1.2192 2.3876)
			(drill oval 0.508 1.524
				(offset 0 -0.199898)
			)
			(layers "*.Cu" "*.Mask")
			(remove_unused_layers no)
			(net "GND")
			(clearance 0.1524)
			(thermal_gap 0.1524)
		)
	)
)
